(kicad_pcb
	(version 20260206)
	(generator "pcbnew")
	(generator_version "10.0")
	(general
		(thickness 1.6)
		(legacy_teardrops no)
	)
	(paper "A4")
	(title_block
		(title "pdpb — Lightning_PDPB_BRD.brd")
		(comment 1 "Lightning (Wiwynn / Facebook NVMe JBOF) / footprints 51-57 of 1140")
	)
	(layers
		(0 "F.Cu" signal "TOP")
		(4 "In1.Cu" signal "L2GND")
		(6 "In2.Cu" signal "L3")
		(8 "In3.Cu" signal "L4VCC")
		(10 "In4.Cu" signal "L5VCC")
		(12 "In5.Cu" signal "L6")
		(14 "In6.Cu" signal "L7GND")
		(2 "B.Cu" signal "BOTTOM")
		(9 "F.Adhes" user "F.Adhesive")
		(11 "B.Adhes" user "B.Adhesive")
		(13 "F.Paste" user "Package Geometry/Pastemask Top")
		(15 "B.Paste" user "Package Geometry/Pastemask Bottom")
		(5 "F.SilkS" user "Ref Des/Silkscreen Top")
		(7 "B.SilkS" user "Ref Des/Silkscreen Bottom")
		(1 "F.Mask" user "Board Geometry/Soldermask Top")
		(3 "B.Mask" user "Board Geometry/Soldermask Bottom")
		(17 "Dwgs.User" user "User.Drawings")
		(19 "Cmts.User" user "User.Comments")
		(21 "Eco1.User" user "User.Eco1")
		(23 "Eco2.User" user "User.Eco2")
		(25 "Edge.Cuts" user "Board Geometry/Outline")
		(27 "Margin" user)
		(31 "F.CrtYd" user "Package Geometry/Place Bound Top")
		(29 "B.CrtYd" user "Package Geometry/Place Bound Bottom")
		(35 "F.Fab" user "Ref Des/Assembly Top")
		(33 "B.Fab" user "Ref Des/Assembly Bottom")
	)
	(footprint ""
		(layer "F.Cu")
		(at 93.599 -109.474 180)
		(property "Reference" "C9433"
			(at 0 0 180)
			(layer "F.SilkS")
			(hide yes)
			(effects
				(font
					(size 1.27 1.27)
				)
			)
		)
		(property "Value" "SCD1U16V2KX-3GP"
			(at 1.1811 -2.7051 180)
			(unlocked yes)
			(layer "F.Fab")
			(hide yes)
			(effects
				(font
					(size 1.016 1.016)
					(thickness 0.1524)
				)
			)
		)
		(property "Device Type" "C402H22"
			(at 1.1811 -4.2291 180)
			(unlocked yes)
			(layer "F.Fab")
			(hide yes)
			(effects
				(font
					(size 1.016 1.016)
					(thickness 0.1524)
				)
			)
		)
		(duplicate_pad_numbers_are_jumpers no)
		(fp_rect
			(start -0.4318 0.9525)
			(end 0.4318 -0.9525)
			(stroke
				(width 0)
				(type default)
			)
			(fill no)
			(layer "F.CrtYd")
		)
		(fp_rect
			(start -0.4318 0.9525)
			(end 0.4318 -0.9525)
			(stroke
				(width 0)
				(type default)
			)
			(fill no)
			(layer "F.Fab")
		)
		(pad "1" smd custom
			(at 0 -0.4445 180)
			(size 0.1524 0.1524)
			(layers "F.Cu" "F.Mask" "F.Paste")
			(net "VDD_DIFF_4")
			(options
				(clearance outline)
				(anchor circle)
			)
			(primitives
				(gr_poly
					(pts
						(arc
							(start 0.3048 -0.2032)
							(mid 0.275042 -0.275042)
							(end 0.2032 -0.3048)
						)
						(arc
							(start -0.2032 -0.3048)
							(mid -0.275042 -0.275042)
							(end -0.3048 -0.2032)
						)
						(arc
							(start -0.3048 0.2032)
							(mid -0.275042 0.275042)
							(end -0.2032 0.3048)
						)
						(arc
							(start 0.2032 0.3048)
							(mid 0.275042 0.275042)
							(end 0.3048 0.2032)
						)
					)
					(width 0)
					(fill yes)
				)
			)
		)
		(pad "2" smd custom
			(at 0 0.4445 180)
			(size 0.1524 0.1524)
			(layers "F.Cu" "F.Mask" "F.Paste")
			(net "GND")
			(options
				(clearance outline)
				(anchor circle)
			)
			(primitives
				(gr_poly
					(pts
						(arc
							(start 0.3048 -0.2032)
							(mid 0.275042 -0.275042)
							(end 0.2032 -0.3048)
						)
						(arc
							(start -0.2032 -0.3048)
							(mid -0.275042 -0.275042)
							(end -0.3048 -0.2032)
						)
						(arc
							(start -0.3048 0.2032)
							(mid -0.275042 0.275042)
							(end -0.2032 0.3048)
						)
						(arc
							(start 0.2032 0.3048)
							(mid 0.275042 0.275042)
							(end 0.3048 0.2032)
						)
					)
					(width 0)
					(fill yes)
				)
			)
		)
	)
	(footprint ""
		(layer "F.Cu")
		(at 21.9964 -474.3196 90)
		(property "Reference" "R9847"
			(at 0 0 90)
			(layer "F.SilkS")
			(hide yes)
			(effects
				(font
					(size 1.27 1.27)
				)
			)
		)
		(property "Value" "0R2J-2-GP"
			(at 0.064008 -3.993896 90)
			(unlocked yes)
			(layer "F.Fab")
			(hide yes)
			(effects
				(font
					(size 1.016 1.016)
					(thickness 0.1524)
				)
			)
		)
		(property "Device Type" "R402H16"
			(at 0.064008 -5.517896 90)
			(unlocked yes)
			(layer "F.Fab")
			(hide yes)
			(effects
				(font
					(size 1.016 1.016)
					(thickness 0.1524)
				)
			)
		)
		(duplicate_pad_numbers_are_jumpers no)
		(fp_line
			(start 0.508 -0.9398)
			(end -0.508 -0.9398)
			(stroke
				(width 0.1524)
				(type default)
			)
			(layer "F.SilkS")
		)
		(fp_line
			(start -0.508 -0.9398)
			(end -0.508 0.9398)
			(stroke
				(width 0.1524)
				(type default)
			)
			(layer "F.SilkS")
		)
		(fp_rect
			(start -0.508 0.9398)
			(end 0.508 -0.9398)
			(stroke
				(width 0)
				(type default)
			)
			(fill no)
			(layer "F.CrtYd")
		)
		(fp_rect
			(start -0.508 0.9398)
			(end 0.508 -0.9398)
			(stroke
				(width 0)
				(type default)
			)
			(fill no)
			(layer "F.Fab")
		)
		(pad "1" smd custom
			(at 0 -0.4445 90)
			(size 0.1397 0.1397)
			(layers "F.Cu" "F.Mask" "F.Paste")
			(net "ATTN_LED_DR10_AND")
			(options
				(clearance outline)
				(anchor circle)
			)
			(primitives
				(gr_poly
					(pts
						(arc
							(start -0.1778 -0.2794)
							(mid -0.249642 -0.249642)
							(end -0.2794 -0.1778)
						)
						(arc
							(start -0.2794 0.1778)
							(mid -0.249642 0.249642)
							(end -0.1778 0.2794)
						)
						(arc
							(start 0.1778 0.2794)
							(mid 0.249642 0.249642)
							(end 0.2794 0.1778)
						)
						(arc
							(start 0.2794 -0.1778)
							(mid 0.249642 -0.249642)
							(end 0.1778 -0.2794)
						)
					)
					(width 0)
					(fill yes)
				)
			)
		)
		(pad "2" smd custom
			(at 0 0.4445 90)
			(size 0.1397 0.1397)
			(layers "F.Cu" "F.Mask" "F.Paste")
			(net "ATTN_LED_DR10_AND_R")
			(options
				(clearance outline)
				(anchor circle)
			)
			(primitives
				(gr_poly
					(pts
						(arc
							(start -0.1778 -0.2794)
							(mid -0.249642 -0.249642)
							(end -0.2794 -0.1778)
						)
						(arc
							(start -0.2794 0.1778)
							(mid -0.249642 0.249642)
							(end -0.1778 0.2794)
						)
						(arc
							(start 0.1778 0.2794)
							(mid 0.249642 0.249642)
							(end 0.2794 0.1778)
						)
						(arc
							(start 0.2794 -0.1778)
							(mid 0.249642 -0.249642)
							(end 0.1778 -0.2794)
						)
					)
					(width 0)
					(fill yes)
				)
			)
		)
	)
	(footprint ""
		(layer "F.Cu")
		(at 26.7716 -8.4074 -90)
		(property "Reference" "R9249"
			(at 0 0 270)
			(layer "F.SilkS")
			(hide yes)
			(effects
				(font
					(size 1.27 1.27)
				)
			)
		)
		(property "Value" "2R2010F-GP"
			(at 0.0762 -4.5466 270)
			(unlocked yes)
			(layer "F.Fab")
			(hide yes)
			(effects
				(font
					(size 1.016 1.016)
					(thickness 0.1524)
				)
			)
		)
		(property "Device Type" "R2010H26"
			(at 0.0762 -6.1468 270)
			(unlocked yes)
			(layer "F.Fab")
			(hide yes)
			(effects
				(font
					(size 1.016 1.016)
					(thickness 0.1524)
				)
			)
		)
		(duplicate_pad_numbers_are_jumpers no)
		(fp_line
			(start -3.302 1.651)
			(end 3.302 1.651)
			(stroke
				(width 0.1524)
				(type default)
			)
			(layer "F.SilkS")
		)
		(fp_line
			(start 3.302 1.651)
			(end 3.302 -1.651)
			(stroke
				(width 0.1524)
				(type default)
			)
			(layer "F.SilkS")
		)
		(fp_line
			(start -3.302 -1.651)
			(end -3.302 1.651)
			(stroke
				(width 0.1524)
				(type default)
			)
			(layer "F.SilkS")
		)
		(fp_line
			(start 3.302 -1.651)
			(end -3.302 -1.651)
			(stroke
				(width 0.1524)
				(type default)
			)
			(layer "F.SilkS")
		)
		(fp_poly
			(pts
				(xy -3.3782 1.7272) (xy 3.3782 1.7272) (xy 3.3782 -1.7272) (xy -3.3782 -1.7272)
			)
			(stroke
				(width 0)
				(type default)
			)
			(fill no)
			(layer "F.CrtYd")
		)
		(fp_poly
			(pts
				(xy 3.3782 -1.7272) (xy -3.3782 -1.7272) (xy -3.3782 1.7272) (xy 3.3782 1.7272)
			)
			(stroke
				(width 0)
				(type default)
			)
			(fill no)
			(layer "F.Fab")
		)
		(pad "1" smd rect
			(at -2.3495 0 270)
			(size 1.143 2.794)
			(layers "F.Cu" "F.Mask" "F.Paste")
			(net "P12V_SSD14")
		)
		(pad "2" smd rect
			(at 2.3495 0 270)
			(size 1.143 2.794)
			(layers "F.Cu" "F.Mask" "F.Paste")
			(net "12V_PRECH_SSD14")
		)
	)
	(footprint ""
		(layer "F.Cu")
		(at 78.8162 -432.2445)
		(property "Reference" "R9960"
			(at 0 0 0)
			(layer "F.SilkS")
			(hide yes)
			(effects
				(font
					(size 1.27 1.27)
				)
			)
		)
		(property "Value" "470R2F-GP"
			(at 0.064008 -3.993896 0)
			(unlocked yes)
			(layer "F.Fab")
			(hide yes)
			(effects
				(font
					(size 1.016 1.016)
					(thickness 0.1524)
				)
			)
		)
		(property "Device Type" "R402H16"
			(at 0.064008 -5.517896 0)
			(unlocked yes)
			(layer "F.Fab")
			(hide yes)
			(effects
				(font
					(size 1.016 1.016)
					(thickness 0.1524)
				)
			)
		)
		(duplicate_pad_numbers_are_jumpers no)
		(fp_line
			(start -0.508 -0.9398)
			(end -0.508 0.9398)
			(stroke
				(width 0.1524)
				(type default)
			)
			(layer "F.SilkS")
		)
		(fp_line
			(start 0.508 -0.9398)
			(end -0.508 -0.9398)
			(stroke
				(width 0.1524)
				(type default)
			)
			(layer "F.SilkS")
		)
		(fp_rect
			(start -0.508 0.9398)
			(end 0.508 -0.9398)
			(stroke
				(width 0)
				(type default)
			)
			(fill no)
			(layer "F.CrtYd")
		)
		(fp_rect
			(start -0.508 0.9398)
			(end 0.508 -0.9398)
			(stroke
				(width 0)
				(type default)
			)
			(fill no)
			(layer "F.Fab")
		)
		(pad "1" smd custom
			(at 0 -0.4445)
			(size 0.1397 0.1397)
			(layers "F.Cu" "F.Mask" "F.Paste")
			(net "VDD_DIFF_1")
			(options
				(clearance outline)
				(anchor circle)
			)
			(primitives
				(gr_poly
					(pts
						(arc
							(start -0.1778 -0.2794)
							(mid -0.249642 -0.249642)
							(end -0.2794 -0.1778)
						)
						(arc
							(start -0.2794 0.1778)
							(mid -0.249642 0.249642)
							(end -0.1778 0.2794)
						)
						(arc
							(start 0.1778 0.2794)
							(mid 0.249642 0.249642)
							(end 0.2794 0.1778)
						)
						(arc
							(start 0.2794 -0.1778)
							(mid 0.249642 -0.249642)
							(end 0.1778 -0.2794)
						)
					)
					(width 0)
					(fill yes)
				)
			)
		)
		(pad "2" smd custom
			(at 0 0.4445)
			(size 0.1397 0.1397)
			(layers "F.Cu" "F.Mask" "F.Paste")
			(net "PE_100M_CLK4_P")
			(options
				(clearance outline)
				(anchor circle)
			)
			(primitives
				(gr_poly
					(pts
						(arc
							(start -0.1778 -0.2794)
							(mid -0.249642 -0.249642)
							(end -0.2794 -0.1778)
						)
						(arc
							(start -0.2794 0.1778)
							(mid -0.249642 0.249642)
							(end -0.1778 0.2794)
						)
						(arc
							(start 0.1778 0.2794)
							(mid 0.249642 0.249642)
							(end 0.2794 0.1778)
						)
						(arc
							(start 0.2794 -0.1778)
							(mid 0.249642 -0.249642)
							(end 0.1778 -0.2794)
						)
					)
					(width 0)
					(fill yes)
				)
			)
		)
	)
	(footprint ""
		(layer "F.Cu")
		(at 217.297 -393.573 180)
		(property "Reference" "SR1094"
			(at 0 0 180)
			(layer "F.SilkS")
			(hide yes)
			(effects
				(font
					(size 1.27 1.27)
				)
			)
		)
		(property "Value" "4K7R2F-GP"
			(at 0.064008 -3.993896 180)
			(unlocked yes)
			(layer "F.Fab")
			(hide yes)
			(effects
				(font
					(size 1.016 1.016)
					(thickness 0.1524)
				)
			)
		)
		(property "Device Type" "R402H16"
			(at 0.064008 -5.517896 180)
			(unlocked yes)
			(layer "F.Fab")
			(hide yes)
			(effects
				(font
					(size 1.016 1.016)
					(thickness 0.1524)
				)
			)
		)
		(duplicate_pad_numbers_are_jumpers no)
		(fp_line
			(start 0.508 -0.9398)
			(end -0.508 -0.9398)
			(stroke
				(width 0.1524)
				(type default)
			)
			(layer "F.SilkS")
		)
		(fp_line
			(start -0.508 -0.9398)
			(end -0.508 0.9398)
			(stroke
				(width 0.1524)
				(type default)
			)
			(layer "F.SilkS")
		)
		(fp_rect
			(start -0.508 0.9398)
			(end 0.508 -0.9398)
			(stroke
				(width 0)
				(type default)
			)
			(fill no)
			(layer "F.CrtYd")
		)
		(fp_rect
			(start -0.508 0.9398)
			(end 0.508 -0.9398)
			(stroke
				(width 0)
				(type default)
			)
			(fill no)
			(layer "F.Fab")
		)
		(pad "1" smd custom
			(at 0 -0.4445 180)
			(size 0.1397 0.1397)
			(layers "F.Cu" "F.Mask" "F.Paste")
			(net "DUALPORTEN#1")
			(options
				(clearance outline)
				(anchor circle)
			)
			(primitives
				(gr_poly
					(pts
						(arc
							(start -0.1778 -0.2794)
							(mid -0.249642 -0.249642)
							(end -0.2794 -0.1778)
						)
						(arc
							(start -0.2794 0.1778)
							(mid -0.249642 0.249642)
							(end -0.1778 0.2794)
						)
						(arc
							(start 0.1778 0.2794)
							(mid 0.249642 0.249642)
							(end 0.2794 0.1778)
						)
						(arc
							(start 0.2794 -0.1778)
							(mid 0.249642 -0.249642)
							(end 0.1778 -0.2794)
						)
					)
					(width 0)
					(fill yes)
				)
			)
		)
		(pad "2" smd custom
			(at 0 0.4445 180)
			(size 0.1397 0.1397)
			(layers "F.Cu" "F.Mask" "F.Paste")
			(net "GND")
			(options
				(clearance outline)
				(anchor circle)
			)
			(primitives
				(gr_poly
					(pts
						(arc
							(start -0.1778 -0.2794)
							(mid -0.249642 -0.249642)
							(end -0.2794 -0.1778)
						)
						(arc
							(start -0.2794 0.1778)
							(mid -0.249642 0.249642)
							(end -0.1778 0.2794)
						)
						(arc
							(start 0.1778 0.2794)
							(mid 0.249642 0.249642)
							(end 0.2794 0.1778)
						)
						(arc
							(start 0.2794 -0.1778)
							(mid 0.249642 -0.249642)
							(end 0.1778 -0.2794)
						)
					)
					(width 0)
					(fill yes)
				)
			)
		)
	)
	(footprint ""
		(layer "F.Cu")
		(at 37.6936 -105.8164)
		(property "Reference" "Q21"
			(at 0 0 0)
			(layer "F.SilkS")
			(hide yes)
			(effects
				(font
					(size 1.27 1.27)
				)
			)
		)
		(property "Value" "2N7002A-7-GP"
			(at 0.127 -8.9662 0)
			(unlocked yes)
			(layer "F.Fab")
			(hide yes)
			(effects
				(font
					(size 1.016 1.016)
					(thickness 0.1524)
				)
			)
		)
		(property "Device Type" "SOT23DGS2D4H48"
			(at 0.127 -10.4902 0)
			(unlocked yes)
			(layer "F.Fab")
			(hide yes)
			(effects
				(font
					(size 1.016 1.016)
					(thickness 0.1524)
				)
			)
		)
		(duplicate_pad_numbers_are_jumpers no)
		(fp_line
			(start -1.651 -1.778)
			(end -1.651 1.778)
			(stroke
				(width 0.1524)
				(type default)
			)
			(layer "F.SilkS")
		)
		(fp_line
			(start -1.651 1.778)
			(end 1.651 1.778)
			(stroke
				(width 0.1524)
				(type default)
			)
			(layer "F.SilkS")
		)
		(fp_line
			(start 1.651 -1.778)
			(end -1.651 -1.778)
			(stroke
				(width 0.1524)
				(type default)
			)
			(layer "F.SilkS")
		)
		(fp_line
			(start 1.651 1.778)
			(end 1.651 -1.778)
			(stroke
				(width 0.1524)
				(type default)
			)
			(layer "F.SilkS")
		)
		(fp_poly
			(pts
				(xy -1.778 1.8796) (xy -1.778 -1.8796) (xy 1.778 -1.8796) (xy 1.778 1.8796)
			)
			(stroke
				(width 0)
				(type default)
			)
			(fill no)
			(layer "F.CrtYd")
		)
		(fp_poly
			(pts
				(xy -1.778 1.8796) (xy -1.778 -1.8796) (xy 1.778 -1.8796) (xy 1.778 1.8796)
			)
			(stroke
				(width 0)
				(type default)
			)
			(fill no)
			(layer "F.Fab")
		)
		(pad "D" smd custom
			(at 0 -0.9525)
			(size 0.1905 0.1905)
			(layers "F.Cu" "F.Mask" "F.Paste")
			(net "SW_SSD13_R")
			(options
				(clearance outline)
				(anchor circle)
			)
			(primitives
				(gr_poly
					(pts
						(arc
							(start -0.1778 0.5715)
							(mid -0.321484 0.511984)
							(end -0.381 0.3683)
						)
						(arc
							(start -0.381 -0.3683)
							(mid -0.321484 -0.511984)
							(end -0.1778 -0.5715)
						)
						(arc
							(start 0.1778 -0.5715)
							(mid 0.321484 -0.511984)
							(end 0.381 -0.3683)
						)
						(arc
							(start 0.381 0.3683)
							(mid 0.321484 0.511984)
							(end 0.1778 0.5715)
						)
					)
					(width 0)
					(fill yes)
				)
			)
		)
		(pad "G" smd custom
			(at -0.98425 0.9525)
			(size 0.1905 0.1905)
			(layers "F.Cu" "F.Mask" "F.Paste")
			(net "SSD13_PWREN")
			(options
				(clearance outline)
				(anchor circle)
			)
			(primitives
				(gr_poly
					(pts
						(arc
							(start -0.1778 0.5715)
							(mid -0.321484 0.511984)
							(end -0.381 0.3683)
						)
						(arc
							(start -0.381 -0.3683)
							(mid -0.321484 -0.511984)
							(end -0.1778 -0.5715)
						)
						(arc
							(start 0.1778 -0.5715)
							(mid 0.321484 -0.511984)
							(end 0.381 -0.3683)
						)
						(arc
							(start 0.381 0.3683)
							(mid 0.321484 0.511984)
							(end 0.1778 0.5715)
						)
					)
					(width 0)
					(fill yes)
				)
			)
		)
		(pad "S" smd custom
			(at 0.98425 0.9525)
			(size 0.1905 0.1905)
			(layers "F.Cu" "F.Mask" "F.Paste")
			(net "GND")
			(options
				(clearance outline)
				(anchor circle)
			)
			(primitives
				(gr_poly
					(pts
						(arc
							(start -0.1778 0.5715)
							(mid -0.321484 0.511984)
							(end -0.381 0.3683)
						)
						(arc
							(start -0.381 -0.3683)
							(mid -0.321484 -0.511984)
							(end -0.1778 -0.5715)
						)
						(arc
							(start 0.1778 -0.5715)
							(mid 0.321484 -0.511984)
							(end 0.381 -0.3683)
						)
						(arc
							(start 0.381 0.3683)
							(mid 0.321484 0.511984)
							(end 0.1778 0.5715)
						)
					)
					(width 0)
					(fill yes)
				)
			)
		)
	)
	(footprint ""
		(layer "F.Cu")
		(at 210.693 -454.66)
		(property "Reference" "R324"
			(at 0 0 0)
			(layer "F.SilkS")
			(hide yes)
			(effects
				(font
					(size 1.27 1.27)
				)
			)
		)
		(property "Value" "4K7R2F-GP"
			(at 0.064008 -3.993896 0)
			(unlocked yes)
			(layer "F.Fab")
			(hide yes)
			(effects
				(font
					(size 1.016 1.016)
					(thickness 0.1524)
				)
			)
		)
		(property "Device Type" "R402H16"
			(at 0.064008 -5.517896 0)
			(unlocked yes)
			(layer "F.Fab")
			(hide yes)
			(effects
				(font
					(size 1.016 1.016)
					(thickness 0.1524)
				)
			)
		)
		(duplicate_pad_numbers_are_jumpers no)
		(fp_line
			(start -0.508 -0.9398)
			(end -0.508 0.9398)
			(stroke
				(width 0.1524)
				(type default)
			)
			(layer "F.SilkS")
		)
		(fp_line
			(start 0.508 -0.9398)
			(end -0.508 -0.9398)
			(stroke
				(width 0.1524)
				(type default)
			)
			(layer "F.SilkS")
		)
		(fp_rect
			(start -0.508 0.9398)
			(end 0.508 -0.9398)
			(stroke
				(width 0)
				(type default)
			)
			(fill no)
			(layer "F.CrtYd")
		)
		(fp_rect
			(start -0.508 0.9398)
			(end 0.508 -0.9398)
			(stroke
				(width 0)
				(type default)
			)
			(fill no)
			(layer "F.Fab")
		)
		(pad "1" smd custom
			(at 0 -0.4445)
			(size 0.1397 0.1397)
			(layers "F.Cu" "F.Mask" "F.Paste")
			(net "I2C_B_TMP2_A1")
			(options
				(clearance outline)
				(anchor circle)
			)
			(primitives
				(gr_poly
					(pts
						(arc
							(start -0.1778 -0.2794)
							(mid -0.249642 -0.249642)
							(end -0.2794 -0.1778)
						)
						(arc
							(start -0.2794 0.1778)
							(mid -0.249642 0.249642)
							(end -0.1778 0.2794)
						)
						(arc
							(start 0.1778 0.2794)
							(mid 0.249642 0.249642)
							(end 0.2794 0.1778)
						)
						(arc
							(start 0.2794 -0.1778)
							(mid 0.249642 -0.249642)
							(end 0.1778 -0.2794)
						)
					)
					(width 0)
					(fill yes)
				)
			)
		)
		(pad "2" smd custom
			(at 0 0.4445)
			(size 0.1397 0.1397)
			(layers "F.Cu" "F.Mask" "F.Paste")
			(net "GND")
			(options
				(clearance outline)
				(anchor circle)
			)
			(primitives
				(gr_poly
					(pts
						(arc
							(start -0.1778 -0.2794)
							(mid -0.249642 -0.249642)
							(end -0.2794 -0.1778)
						)
						(arc
							(start -0.2794 0.1778)
							(mid -0.249642 0.249642)
							(end -0.1778 0.2794)
						)
						(arc
							(start 0.1778 0.2794)
							(mid 0.249642 0.249642)
							(end 0.2794 0.1778)
						)
						(arc
							(start 0.2794 -0.1778)
							(mid 0.249642 -0.249642)
							(end 0.1778 -0.2794)
						)
					)
					(width 0)
					(fill yes)
				)
			)
		)
	)
)
